# BASEBOARD_FAB2 (Tioga Pass) — schematic netlist excerpt (pin names and nets, part order shuffled) for the footprints in the layout excerpt that follows; sources: Cadence DE-HDL packaged netlist, KiCad conversion of Wiwynn_Tioga_Pass_MB.brd

T1P14  TPAD-DIFF-4P-GP  pkg DISCRET-GB3  page 256
  \1\  = L1_95OHM_6INCH_DP
  \2\  = L1_95OHM_6INCH_DN
  GND1  = GND
  GND2  = GND

C4A19  CAP  10UF 16V 10% X6S  pkg 0805  page 234 : A = VR_FET_SW_P12V_STBY_PVPP_KLM ; B = GND
R9F61  RES  10.0K 1% CHIP  pkg 0402  page 145 : A = P3V3_STBY ; B = PU_24M_OSC_OE

(kicad_pcb
	(version 20260206)
	(generator "pcbnew")
	(generator_version "10.0")
	(general
		(thickness 1.6)
		(legacy_teardrops no)
	)
	(paper "A4")
	(title_block
		(title "Wiwynn_Tioga_Pass_MB.brd")
		(comment 1 "Tioga Pass / footprints 1322-1324 of 4770")
	)
	(layers
		(0 "F.Cu" signal "TOP")
		(4 "In1.Cu" signal "L2GND")
		(6 "In2.Cu" signal "L3")
		(8 "In3.Cu" signal "L4GND")
		(10 "In4.Cu" signal "L5")
		(12 "In5.Cu" signal "L6GND")
		(14 "In6.Cu" signal "L7VCC")
		(16 "In7.Cu" signal "L8VCC")
		(18 "In8.Cu" signal "L9GND")
		(20 "In9.Cu" signal "L10")
		(22 "In10.Cu" signal "L11GND")
		(24 "In11.Cu" signal "L12")
		(26 "In12.Cu" signal "L13GND")
		(2 "B.Cu" signal "BOTTOM")
		(9 "F.Adhes" user "F.Adhesive")
		(11 "B.Adhes" user "B.Adhesive")
		(13 "F.Paste" user "Package Geometry/Pastemask Top")
		(15 "B.Paste" user "Package Geometry/Pastemask Bottom")
		(5 "F.SilkS" user "Ref Des/Silkscreen Top")
		(7 "B.SilkS" user "Ref Des/Silkscreen Bottom")
		(1 "F.Mask" user "Board Geometry/Soldermask Top")
		(3 "B.Mask" user "Board Geometry/Soldermask Bottom")
		(17 "Dwgs.User" user "User.Drawings")
		(19 "Cmts.User" user "User.Comments")
		(21 "Eco1.User" user "User.Eco1")
		(23 "Eco2.User" user "User.Eco2")
		(25 "Edge.Cuts" user "Board Geometry/Outline")
		(27 "Margin" user)
		(31 "F.CrtYd" user "Package Geometry/Place Bound Top")
		(29 "B.CrtYd" user "Package Geometry/Place Bound Bottom")
		(35 "F.Fab" user "Ref Des/Assembly Top")
		(33 "B.Fab" user "Ref Des/Assembly Bottom")
	)
	(footprint ""
		(layer "F.Cu")
		(at 183.3626 -136.4234 180)
		(property "Reference" "C4A19"
			(at 0 0 180)
			(layer "F.SilkS")
			(hide yes)
			(effects
				(font
					(size 1.27 1.27)
				)
			)
		)
		(property "Value" ""
			(at 0 0 180)
			(layer "F.Fab")
			(effects
				(font
					(size 1.27 1.27)
				)
			)
		)
		(duplicate_pad_numbers_are_jumpers no)
		(fp_poly
			(pts
				(xy -0.7239 -0.2159) (xy 0.7239 -0.2159) (xy 0.7239 1.9939) (xy -0.7239 1.9939)
			)
			(stroke
				(width 0)
				(type default)
			)
			(fill no)
			(layer "F.CrtYd")
		)
		(fp_line
			(start 0.7239 1.9939)
			(end 0.7239 -0.2159)
			(stroke
				(width 0.1)
				(type default)
			)
			(layer "F.Fab")
		)
		(fp_line
			(start 0.7239 -0.2159)
			(end -0.7239 -0.2159)
			(stroke
				(width 0.1)
				(type default)
			)
			(layer "F.Fab")
		)
		(fp_line
			(start -0.7239 1.9939)
			(end 0.7239 1.9939)
			(stroke
				(width 0.1)
				(type default)
			)
			(layer "F.Fab")
		)
		(fp_line
			(start -0.7239 -0.2159)
			(end -0.7239 1.9939)
			(stroke
				(width 0.1)
				(type default)
			)
			(layer "F.Fab")
		)
		(pad "1" smd rect
			(at 0 0 180)
			(size 1.27 1.016)
			(layers "F.Cu" "F.Mask" "F.Paste")
			(net "VR_FET_SW_P12V_STBY_PVPP_KLM")
		)
		(pad "2" smd rect
			(at 0 1.778 180)
			(size 1.27 1.016)
			(layers "F.Cu" "F.Mask" "F.Paste")
			(net "GND")
		)
		(zone
			(layer "F.Cu")
			(hatch none 0.5)
			(connect_pads
				(clearance 0)
			)
			(min_thickness 0.25)
			(keepout
				(tracks not_allowed)
				(vias allowed)
				(pads allowed)
				(copperpour not_allowed)
				(footprints allowed)
			)
			(placement
				(enabled no)
				(sheetname "")
			)
			(fill
				(thermal_gap 0.5)
				(thermal_bridge_width 0.5)
				(island_removal_mode 0)
			)
			(polygon
				(pts
					(xy 183.9976 -136.9314) (xy 182.7276 -136.9314) (xy 182.7276 -137.6934) (xy 183.9976 -137.6934)
				)
			)
		)
	)
	(footprint ""
		(layer "F.Cu")
		(at 430.972468 -50.482246 -90)
		(property "Reference" "R9F61"
			(at 0 0 270)
			(layer "F.SilkS")
			(hide yes)
			(effects
				(font
					(size 1.27 1.27)
				)
			)
		)
		(property "Value" ""
			(at 0 0 270)
			(layer "F.Fab")
			(effects
				(font
					(size 1.27 1.27)
				)
			)
		)
		(duplicate_pad_numbers_are_jumpers no)
		(fp_poly
			(pts
				(xy -0.2794 -0.1016) (xy 0.2794 -0.1016) (xy 0.2794 0.9906) (xy -0.2794 0.9906)
			)
			(stroke
				(width 0)
				(type default)
			)
			(fill no)
			(layer "F.CrtYd")
		)
		(fp_line
			(start -0.2794 0.9906)
			(end 0.2794 0.9906)
			(stroke
				(width 0.1)
				(type default)
			)
			(layer "F.Fab")
		)
		(fp_line
			(start 0.2794 0.9906)
			(end 0.2794 -0.1016)
			(stroke
				(width 0.1)
				(type default)
			)
			(layer "F.Fab")
		)
		(fp_line
			(start -0.2794 -0.1016)
			(end -0.2794 0.9906)
			(stroke
				(width 0.1)
				(type default)
			)
			(layer "F.Fab")
		)
		(fp_line
			(start 0.2794 -0.1016)
			(end -0.2794 -0.1016)
			(stroke
				(width 0.1)
				(type default)
			)
			(layer "F.Fab")
		)
		(pad "1" smd rect
			(at 0 0 270)
			(size 0.508 0.508)
			(layers "F.Cu" "F.Mask" "F.Paste")
			(net "P3V3_STBY")
		)
		(pad "2" smd rect
			(at 0 0.889 270)
			(size 0.508 0.508)
			(layers "F.Cu" "F.Mask" "F.Paste")
			(net "PU_24M_OSC_OE")
		)
		(zone
			(layer "F.Cu")
			(hatch none 0.5)
			(connect_pads
				(clearance 0)
			)
			(min_thickness 0.25)
			(keepout
				(tracks not_allowed)
				(vias allowed)
				(pads allowed)
				(copperpour not_allowed)
				(footprints allowed)
			)
			(placement
				(enabled no)
				(sheetname "")
			)
			(fill
				(thermal_gap 0.5)
				(thermal_bridge_width 0.5)
				(island_removal_mode 0)
			)
			(polygon
				(pts
					(xy 430.337468 -50.736246) (xy 430.337468 -50.228246) (xy 430.718468 -50.228246) (xy 430.718468 -50.736246)
				)
			)
		)
		(zone
			(layer "F.Cu")
			(hatch none 0.5)
			(connect_pads
				(clearance 0)
			)
			(min_thickness 0.25)
			(keepout
				(tracks allowed)
				(vias not_allowed)
				(pads allowed)
				(copperpour not_allowed)
				(footprints allowed)
			)
			(placement
				(enabled no)
				(sheetname "")
			)
			(fill
				(thermal_gap 0.5)
				(thermal_bridge_width 0.5)
				(island_removal_mode 0)
			)
			(polygon
				(pts
					(xy 430.718468 -50.736246) (xy 430.718468 -50.228246) (xy 430.337468 -50.228246) (xy 430.337468 -50.736246)
				)
			)
		)
	)
	(footprint ""
		(layer "F.Cu")
		(at 287.168082 12.01039 -90)
		(property "Reference" "T1P14"
			(at 0 0 270)
			(layer "F.SilkS")
			(hide yes)
			(effects
				(font
					(size 1.27 1.27)
				)
			)
		)
		(property "Value" "*"
			(at -3.302 1.12395 270)
			(unlocked yes)
			(layer "F.Fab")
			(hide yes)
			(effects
				(font
					(size 0.889 0.889)
					(thickness 0.1524)
				)
			)
		)
		(property "Device Type" "TPAD-DIFF-4P-GP_DISCRET-GB3-TPA"
			(at -3.302 -0.40005 270)
			(unlocked yes)
			(layer "F.Fab")
			(hide yes)
			(effects
				(font
					(size 0.889 0.889)
					(thickness 0.1524)
				)
			)
		)
		(duplicate_pad_numbers_are_jumpers no)
		(fp_line
			(start -2.286 2.286)
			(end 2.286 2.286)
			(stroke
				(width 0.1524)
				(type default)
			)
			(layer "F.SilkS")
		)
		(fp_line
			(start 2.286 2.286)
			(end 2.286 -2.286)
			(stroke
				(width 0.1524)
				(type default)
			)
			(layer "F.SilkS")
		)
		(fp_line
			(start -2.286 -2.286)
			(end -2.286 2.286)
			(stroke
				(width 0.1524)
				(type default)
			)
			(layer "F.SilkS")
		)
		(fp_line
			(start 2.286 -2.286)
			(end -2.286 -2.286)
			(stroke
				(width 0.1524)
				(type default)
			)
			(layer "F.SilkS")
		)
		(fp_line
			(start -2.413 -2.413)
			(end -2.413 -1.143)
			(stroke
				(width 0.4064)
				(type default)
			)
			(layer "F.SilkS")
		)
		(fp_line
			(start -1.143 -2.413)
			(end -2.413 -2.413)
			(stroke
				(width 0.4064)
				(type default)
			)
			(layer "F.SilkS")
		)
		(fp_rect
			(start -2.54 2.54)
			(end 2.54 -2.54)
			(stroke
				(width 0)
				(type default)
			)
			(fill no)
			(layer "F.CrtYd")
		)
		(fp_rect
			(start -2.54 2.54)
			(end 2.54 -2.54)
			(stroke
				(width 0)
				(type default)
			)
			(fill no)
			(layer "F.Fab")
		)
		(pad "1" thru_hole circle
			(at -1.27 -1.27 270)
			(size 1.524 1.524)
			(drill 0.9144)
			(layers "*.Cu" "*.Mask")
			(remove_unused_layers no)
			(net "L1_95OHM_6INCH_DP")
			(clearance -0.0508)
			(thermal_gap 0.127)
			(padstack
				(mode front_inner_back)
				(layer "Inner"
					(shape circle)
					(size 1.1684 1.1684)
					(clearance 0.127)
				)
				(layer "B.Cu"
					(shape circle)
					(size 1.524 1.524)
					(clearance -0.0508)
				)
			)
		)
		(pad "2" thru_hole circle
			(at 1.27 -1.27 270)
			(size 1.524 1.524)
			(drill 0.9144)
			(layers "*.Cu" "*.Mask")
			(remove_unused_layers no)
			(net "L1_95OHM_6INCH_DN")
			(clearance -0.0508)
			(thermal_gap 0.127)
			(padstack
				(mode front_inner_back)
				(layer "Inner"
					(shape circle)
					(size 1.1684 1.1684)
					(clearance 0.127)
				)
				(layer "B.Cu"
					(shape circle)
					(size 1.524 1.524)
					(clearance -0.0508)
				)
			)
		)
		(pad "GND1" thru_hole rect
			(at -1.27 1.27 270)
			(size 1.524 1.524)
			(drill 0.9144)
			(layers "*.Cu" "*.Mask")
			(remove_unused_layers no)
			(net "GND")
			(clearance -0.0508)
			(thermal_gap 0.127)
			(padstack
				(mode front_inner_back)
				(layer "Inner"
					(shape circle)
					(size 1.1684 1.1684)
					(clearance 0.127)
				)
				(layer "B.Cu"
					(shape rect)
					(size 1.524 1.524)
					(clearance -0.0508)
				)
			)
		)
		(pad "GND2" thru_hole rect
			(at 1.27 1.27 270)
			(size 1.524 1.524)
			(drill 0.9144)
			(layers "*.Cu" "*.Mask")
			(remove_unused_layers no)
			(net "GND")
			(clearance -0.0508)
			(thermal_gap 0.127)
			(padstack
				(mode front_inner_back)
				(layer "Inner"
					(shape circle)
					(size 1.1684 1.1684)
					(clearance 0.127)
				)
				(layer "B.Cu"
					(shape rect)
					(size 1.524 1.524)
					(clearance -0.0508)
				)
			)
		)
	)
)
